(kicad_pcb
	(version 20260206)
	(generator "pcbnew")
	(generator_version "10.0")
	(general
		(thickness 1.6)
		(legacy_teardrops no)
	)
	(paper "A4")
	(title_block
		(title "pdpb — Lightning_PDPB_BRD.brd")
		(comment 1 "Lightning (Wiwynn / Facebook NVMe JBOF) / footprint 592 of 1140 (J17), pads 115-202 of 202")
	)
	(layers
		(0 "F.Cu" signal "TOP")
		(4 "In1.Cu" signal "L2GND")
		(6 "In2.Cu" signal "L3")
		(8 "In3.Cu" signal "L4VCC")
		(10 "In4.Cu" signal "L5VCC")
		(12 "In5.Cu" signal "L6")
		(14 "In6.Cu" signal "L7GND")
		(2 "B.Cu" signal "BOTTOM")
		(9 "F.Adhes" user "F.Adhesive")
		(11 "B.Adhes" user "B.Adhesive")
		(13 "F.Paste" user "Package Geometry/Pastemask Top")
		(15 "B.Paste" user "Package Geometry/Pastemask Bottom")
		(5 "F.SilkS" user "Ref Des/Silkscreen Top")
		(7 "B.SilkS" user "Ref Des/Silkscreen Bottom")
		(1 "F.Mask" user "Board Geometry/Soldermask Top")
		(3 "B.Mask" user "Board Geometry/Soldermask Bottom")
		(17 "Dwgs.User" user "User.Drawings")
		(19 "Cmts.User" user "User.Comments")
		(21 "Eco1.User" user "User.Eco1")
		(23 "Eco2.User" user "User.Eco2")
		(25 "Edge.Cuts" user "Board Geometry/Outline")
		(27 "Margin" user)
		(31 "F.CrtYd" user "Package Geometry/Place Bound Top")
		(29 "B.CrtYd" user "Package Geometry/Place Bound Bottom")
		(35 "F.Fab" user "Ref Des/Assembly Top")
		(33 "B.Fab" user "Ref Des/Assembly Bottom")
	)
	(footprint ""
		(layer "F.Cu")
		(at 2.999994 -425.141898 90)
		(property "Reference" "J17"
			(at 0 0 90)
			(layer "F.SilkS")
			(hide yes)
			(effects
				(font
					(size 1.27 1.27)
				)
			)
		)
		(property "Value" "PCISLT200-5-GP-U"
			(at -48.7045 -6.7818 90)
			(unlocked yes)
			(layer "F.Fab")
			(hide yes)
			(effects
				(font
					(size 1.016 1.016)
					(thickness 0.1524)
				)
			)
		)
		(property "Device Type" "G639F200221431HR-U"
			(at -48.7045 -8.3058 90)
			(unlocked yes)
			(layer "F.Fab")
			(hide yes)
			(effects
				(font
					(size 1.016 1.016)
					(thickness 0.1524)
				)
			)
		)
		(duplicate_pad_numbers_are_jumpers no)
		(pad "B13" smd rect
			(at -31.599886 -1.131062 90)
			(size 0.508 2.4892)
			(drill
				(offset 0 0.381)
			)
			(layers "F.Cu" "F.Mask" "F.Paste")
			(net "GND")
		)
		(pad "B14" smd rect
			(at -30.80004 -1.131062 90)
			(size 0.508 2.4892)
			(drill
				(offset 0 0.381)
			)
			(layers "F.Cu" "F.Mask" "F.Paste")
			(net "GND")
		)
		(pad "B15" smd rect
			(at -29.99994 -1.131062 90)
			(size 0.508 2.4892)
			(drill
				(offset 0 0.381)
			)
			(layers "F.Cu" "F.Mask" "F.Paste")
			(net "PE_RX3_DR1_N")
		)
		(pad "B16" smd rect
			(at -29.200094 -1.131062 90)
			(size 0.508 2.4892)
			(drill
				(offset 0 0.381)
			)
			(layers "F.Cu" "F.Mask" "F.Paste")
			(net "PE_RX3_DR1_P")
		)
		(pad "B17" smd rect
			(at -28.399994 -1.131062 90)
			(size 0.508 2.4892)
			(drill
				(offset 0 0.381)
			)
			(layers "F.Cu" "F.Mask" "F.Paste")
			(net "GND")
		)
		(pad "B18" smd rect
			(at -27.599894 -1.131062 90)
			(size 0.508 2.4892)
			(drill
				(offset 0 0.381)
			)
			(layers "F.Cu" "F.Mask" "F.Paste")
			(net "GND")
		)
		(pad "B19" smd rect
			(at -26.800048 -1.131062 90)
			(size 0.508 2.4892)
			(drill
				(offset 0 0.381)
			)
			(layers "F.Cu" "F.Mask" "F.Paste")
			(net "PE_RX4_DR1_N")
		)
		(pad "B20" smd rect
			(at -25.999948 -1.131062 90)
			(size 0.508 2.4892)
			(drill
				(offset 0 0.381)
			)
			(layers "F.Cu" "F.Mask" "F.Paste")
			(net "PE_RX4_DR1_P")
		)
		(pad "B21" smd rect
			(at -25.200102 -1.131062 90)
			(size 0.508 2.4892)
			(drill
				(offset 0 0.381)
			)
			(layers "F.Cu" "F.Mask" "F.Paste")
			(net "GND")
		)
		(pad "B22" smd rect
			(at -24.400002 -1.131062 90)
			(size 0.508 2.4892)
			(drill
				(offset 0 0.381)
			)
			(layers "F.Cu" "F.Mask" "F.Paste")
			(net "SSD10_PWREN")
		)
		(pad "B23" smd rect
			(at -23.599902 -1.131062 90)
			(size 0.508 2.4892)
			(drill
				(offset 0 0.381)
			)
			(layers "F.Cu" "F.Mask" "F.Paste")
			(net "ATTN_LED_DR10_N")
		)
		(pad "B24" smd rect
			(at -22.800056 -1.131062 90)
			(size 0.508 2.4892)
			(drill
				(offset 0 0.381)
			)
			(layers "F.Cu" "F.Mask" "F.Paste")
			(net "SSD10_CLK0_OE_R_N")
		)
		(pad "B25" smd rect
			(at -21.999956 -1.131062 90)
			(size 0.508 2.4892)
			(drill
				(offset 0 0.381)
			)
			(layers "F.Cu" "F.Mask" "F.Paste")
			(net "GND")
		)
		(pad "B26" smd rect
			(at -21.20011 -1.131062 90)
			(size 0.508 2.4892)
			(drill
				(offset 0 0.381)
			)
			(layers "F.Cu" "F.Mask" "F.Paste")
			(net "PE_RX1_DR10_P")
		)
		(pad "B27" smd rect
			(at -20.40001 -1.131062 90)
			(size 0.508 2.4892)
			(drill
				(offset 0 0.381)
			)
			(layers "F.Cu" "F.Mask" "F.Paste")
			(net "PE_RX1_DR10_N")
		)
		(pad "B28" smd rect
			(at -19.59991 -1.131062 90)
			(size 0.508 2.4892)
			(drill
				(offset 0 0.381)
			)
			(layers "F.Cu" "F.Mask" "F.Paste")
			(net "GND")
		)
		(pad "B29" smd rect
			(at -18.800064 -1.131062 90)
			(size 0.508 2.4892)
			(drill
				(offset 0 0.381)
			)
			(layers "F.Cu" "F.Mask" "F.Paste")
			(net "GND")
		)
		(pad "B30" smd rect
			(at -17.999964 -1.131062 90)
			(size 0.508 2.4892)
			(drill
				(offset 0 0.381)
			)
			(layers "F.Cu" "F.Mask" "F.Paste")
			(net "PE_RX2_DR10_P")
		)
		(pad "B31" smd rect
			(at -17.200118 -1.131062 90)
			(size 0.508 2.4892)
			(drill
				(offset 0 0.381)
			)
			(layers "F.Cu" "F.Mask" "F.Paste")
			(net "PE_RX2_DR10_N")
		)
		(pad "B32" smd rect
			(at -16.400018 -1.131062 90)
			(size 0.508 2.4892)
			(drill
				(offset 0 0.381)
			)
			(layers "F.Cu" "F.Mask" "F.Paste")
			(net "GND")
		)
		(pad "B33" smd rect
			(at -15.599918 -1.131062 90)
			(size 0.508 2.4892)
			(drill
				(offset 0 0.381)
			)
			(layers "F.Cu" "F.Mask" "F.Paste")
			(net "GND")
		)
		(pad "B34" smd rect
			(at -14.800072 -1.131062 90)
			(size 0.508 2.4892)
			(drill
				(offset 0 0.381)
			)
			(layers "F.Cu" "F.Mask" "F.Paste")
			(net "PE_RX3_DR10_P")
		)
		(pad "B35" smd rect
			(at -13.999972 -1.131062 90)
			(size 0.508 2.4892)
			(drill
				(offset 0 0.381)
			)
			(layers "F.Cu" "F.Mask" "F.Paste")
			(net "PE_RX3_DR10_N")
		)
		(pad "B36" smd rect
			(at -13.200126 -1.131062 90)
			(size 0.508 2.4892)
			(drill
				(offset 0 0.381)
			)
			(layers "F.Cu" "F.Mask" "F.Paste")
			(net "GND")
		)
		(pad "B37" smd rect
			(at -12.400026 -1.131062 90)
			(size 0.508 2.4892)
			(drill
				(offset 0 0.381)
			)
			(layers "F.Cu" "F.Mask" "F.Paste")
			(net "GND")
		)
		(pad "B38" smd rect
			(at -11.599926 -1.131062 90)
			(size 0.508 2.4892)
			(drill
				(offset 0 0.381)
			)
			(layers "F.Cu" "F.Mask" "F.Paste")
			(net "PE_RX4_DR10_P")
		)
		(pad "B39" smd rect
			(at -10.80008 -1.131062 90)
			(size 0.508 2.4892)
			(drill
				(offset 0 0.381)
			)
			(layers "F.Cu" "F.Mask" "F.Paste")
			(net "PE_RX4_DR10_N")
		)
		(pad "B40" smd rect
			(at -9.99998 -1.131062 90)
			(size 0.508 2.4892)
			(drill
				(offset 0 0.381)
			)
			(layers "F.Cu" "F.Mask" "F.Paste")
			(net "GND")
		)
		(pad "B41" smd rect
			(at -9.19988 -1.131062 90)
			(size 0.508 2.4892)
			(drill
				(offset 0 0.381)
			)
			(layers "F.Cu" "F.Mask" "F.Paste")
			(net "GND")
		)
		(pad "B42" smd rect
			(at -8.400034 -1.131062 90)
			(size 0.508 2.4892)
			(drill
				(offset 0 0.381)
			)
			(layers "F.Cu" "F.Mask" "F.Paste")
			(net "PE_RX1_DR0_N")
		)
		(pad "B43" smd rect
			(at -7.599934 -1.131062 90)
			(size 0.508 2.4892)
			(drill
				(offset 0 0.381)
			)
			(layers "F.Cu" "F.Mask" "F.Paste")
			(net "PE_RX1_DR0_P")
		)
		(pad "B44" smd rect
			(at -6.800088 -1.131062 90)
			(size 0.508 2.4892)
			(drill
				(offset 0 0.381)
			)
			(layers "F.Cu" "F.Mask" "F.Paste")
			(net "GND")
		)
		(pad "B45" smd rect
			(at -2.800096 -1.131062 90)
			(size 0.508 2.4892)
			(drill
				(offset 0 0.381)
			)
			(layers "F.Cu" "F.Mask" "F.Paste")
			(net "GND")
		)
		(pad "B46" smd rect
			(at -1.999996 -1.131062 90)
			(size 0.508 2.4892)
			(drill
				(offset 0 0.381)
			)
			(layers "F.Cu" "F.Mask" "F.Paste")
			(net "PE_RX2_DR0_N")
		)
		(pad "B47" smd rect
			(at -1.199896 -1.131062 90)
			(size 0.508 2.4892)
			(drill
				(offset 0 0.381)
			)
			(layers "F.Cu" "F.Mask" "F.Paste")
			(net "PE_RX2_DR0_P")
		)
		(pad "B48" smd rect
			(at -0.40005 -1.131062 90)
			(size 0.508 2.4892)
			(drill
				(offset 0 0.381)
			)
			(layers "F.Cu" "F.Mask" "F.Paste")
			(net "GND")
		)
		(pad "B49" smd rect
			(at 0.40005 -1.131062 90)
			(size 0.508 2.4892)
			(drill
				(offset 0 0.381)
			)
			(layers "F.Cu" "F.Mask" "F.Paste")
			(net "GND")
		)
		(pad "B50" smd rect
			(at 1.199896 -1.131062 90)
			(size 0.508 2.4892)
			(drill
				(offset 0 0.381)
			)
			(layers "F.Cu" "F.Mask" "F.Paste")
			(net "PE_RX3_DR0_N")
		)
		(pad "B51" smd rect
			(at 1.999996 -1.131062 90)
			(size 0.508 2.4892)
			(drill
				(offset 0 0.381)
			)
			(layers "F.Cu" "F.Mask" "F.Paste")
			(net "PE_RX3_DR0_P")
		)
		(pad "B52" smd rect
			(at 2.800096 -1.131062 90)
			(size 0.508 2.4892)
			(drill
				(offset 0 0.381)
			)
			(layers "F.Cu" "F.Mask" "F.Paste")
			(net "GND")
		)
		(pad "B53" smd rect
			(at 3.599942 -1.131062 90)
			(size 0.508 2.4892)
			(drill
				(offset 0 0.381)
			)
			(layers "F.Cu" "F.Mask" "F.Paste")
			(net "GND")
		)
		(pad "B54" smd rect
			(at 4.400042 -1.131062 90)
			(size 0.508 2.4892)
			(drill
				(offset 0 0.381)
			)
			(layers "F.Cu" "F.Mask" "F.Paste")
			(net "PE_RX4_DR0_N")
		)
		(pad "B55" smd rect
			(at 5.199888 -1.131062 90)
			(size 0.508 2.4892)
			(drill
				(offset 0 0.381)
			)
			(layers "F.Cu" "F.Mask" "F.Paste")
			(net "PE_RX4_DR0_P")
		)
		(pad "B56" smd rect
			(at 5.999988 -1.131062 90)
			(size 0.508 2.4892)
			(drill
				(offset 0 0.381)
			)
			(layers "F.Cu" "F.Mask" "F.Paste")
			(net "GND")
		)
		(pad "B57" smd rect
			(at 6.800088 -1.131062 90)
			(size 0.508 2.4892)
			(drill
				(offset 0 0.381)
			)
			(layers "F.Cu" "F.Mask" "F.Paste")
			(net "SSD5_CLK0_OE_R_N")
		)
		(pad "B58" smd rect
			(at 7.599934 -1.131062 90)
			(size 0.508 2.4892)
			(drill
				(offset 0 0.381)
			)
			(layers "F.Cu" "F.Mask" "F.Paste")
			(net "ATTN_LED_DR5_N")
		)
		(pad "B59" smd rect
			(at 8.400034 -1.131062 90)
			(size 0.508 2.4892)
			(drill
				(offset 0 0.381)
			)
			(layers "F.Cu" "F.Mask" "F.Paste")
			(net "SSD5_PWREN")
		)
		(pad "B60" smd rect
			(at 9.19988 -1.131062 90)
			(size 0.508 2.4892)
			(drill
				(offset 0 0.381)
			)
			(layers "F.Cu" "F.Mask" "F.Paste")
			(net "GND")
		)
		(pad "B61" smd rect
			(at 9.99998 -1.131062 90)
			(size 0.508 2.4892)
			(drill
				(offset 0 0.381)
			)
			(layers "F.Cu" "F.Mask" "F.Paste")
			(net "PE_RX1_DR5_P")
		)
		(pad "B62" smd rect
			(at 10.80008 -1.131062 90)
			(size 0.508 2.4892)
			(drill
				(offset 0 0.381)
			)
			(layers "F.Cu" "F.Mask" "F.Paste")
			(net "PE_RX1_DR5_N")
		)
		(pad "B63" smd rect
			(at 11.599926 -1.131062 90)
			(size 0.508 2.4892)
			(drill
				(offset 0 0.381)
			)
			(layers "F.Cu" "F.Mask" "F.Paste")
			(net "GND")
		)
		(pad "B64" smd rect
			(at 12.400026 -1.131062 90)
			(size 0.508 2.4892)
			(drill
				(offset 0 0.381)
			)
			(layers "F.Cu" "F.Mask" "F.Paste")
			(net "GND")
		)
		(pad "B65" smd rect
			(at 13.200126 -1.131062 90)
			(size 0.508 2.4892)
			(drill
				(offset 0 0.381)
			)
			(layers "F.Cu" "F.Mask" "F.Paste")
			(net "PE_RX2_DR5_P")
		)
		(pad "B66" smd rect
			(at 13.999972 -1.131062 90)
			(size 0.508 2.4892)
			(drill
				(offset 0 0.381)
			)
			(layers "F.Cu" "F.Mask" "F.Paste")
			(net "PE_RX2_DR5_N")
		)
		(pad "B67" smd rect
			(at 14.800072 -1.131062 90)
			(size 0.508 2.4892)
			(drill
				(offset 0 0.381)
			)
			(layers "F.Cu" "F.Mask" "F.Paste")
			(net "GND")
		)
		(pad "B68" smd rect
			(at 15.599918 -1.131062 90)
			(size 0.508 2.4892)
			(drill
				(offset 0 0.381)
			)
			(layers "F.Cu" "F.Mask" "F.Paste")
			(net "GND")
		)
		(pad "B69" smd rect
			(at 16.400018 -1.131062 90)
			(size 0.508 2.4892)
			(drill
				(offset 0 0.381)
			)
			(layers "F.Cu" "F.Mask" "F.Paste")
			(net "PE_RX3_DR5_P")
		)
		(pad "B70" smd rect
			(at 17.200118 -1.131062 90)
			(size 0.508 2.4892)
			(drill
				(offset 0 0.381)
			)
			(layers "F.Cu" "F.Mask" "F.Paste")
			(net "PE_RX3_DR5_N")
		)
		(pad "B71" smd rect
			(at 17.999964 -1.131062 90)
			(size 0.508 2.4892)
			(drill
				(offset 0 0.381)
			)
			(layers "F.Cu" "F.Mask" "F.Paste")
			(net "GND")
		)
		(pad "B72" smd rect
			(at 18.800064 -1.131062 90)
			(size 0.508 2.4892)
			(drill
				(offset 0 0.381)
			)
			(layers "F.Cu" "F.Mask" "F.Paste")
			(net "GND")
		)
		(pad "B73" smd rect
			(at 19.59991 -1.131062 90)
			(size 0.508 2.4892)
			(drill
				(offset 0 0.381)
			)
			(layers "F.Cu" "F.Mask" "F.Paste")
			(net "PE_RX4_DR5_P")
		)
		(pad "B74" smd rect
			(at 20.40001 -1.131062 90)
			(size 0.508 2.4892)
			(drill
				(offset 0 0.381)
			)
			(layers "F.Cu" "F.Mask" "F.Paste")
			(net "PE_RX4_DR5_N")
		)
		(pad "B75" smd rect
			(at 21.20011 -1.131062 90)
			(size 0.508 2.4892)
			(drill
				(offset 0 0.381)
			)
			(layers "F.Cu" "F.Mask" "F.Paste")
			(net "GND")
		)
		(pad "B76" smd rect
			(at 21.999956 -1.131062 90)
			(size 0.508 2.4892)
			(drill
				(offset 0 0.381)
			)
			(layers "F.Cu" "F.Mask" "F.Paste")
			(net "PE_100M_CLK3_C_P")
		)
		(pad "B77" smd rect
			(at 22.800056 -1.131062 90)
			(size 0.508 2.4892)
			(drill
				(offset 0 0.381)
			)
			(layers "F.Cu" "F.Mask" "F.Paste")
			(net "PE_100M_CLK3_C_N")
		)
		(pad "B78" smd rect
			(at 23.599902 -1.131062 90)
			(size 0.508 2.4892)
			(drill
				(offset 0 0.381)
			)
			(layers "F.Cu" "F.Mask" "F.Paste")
			(net "GND")
		)
		(pad "B79" smd rect
			(at 24.400002 -1.131062 90)
			(size 0.508 2.4892)
			(drill
				(offset 0 0.381)
			)
			(layers "F.Cu" "F.Mask" "F.Paste")
			(net "BMC_I2C_SCL_BUF_8")
		)
		(pad "B80" smd rect
			(at 25.200102 -1.131062 90)
			(size 0.508 2.4892)
			(drill
				(offset 0 0.381)
			)
			(layers "F.Cu" "F.Mask" "F.Paste")
			(net "BMC_I2C_SDA_BUF_8")
		)
		(pad "B81" smd rect
			(at 25.999948 -1.131062 90)
			(size 0.508 2.4892)
			(drill
				(offset 0 0.381)
			)
			(layers "F.Cu" "F.Mask" "F.Paste")
			(net "GND")
		)
		(pad "B82" smd rect
			(at 26.800048 -1.131062 90)
			(size 0.508 2.4892)
			(drill
				(offset 0 0.381)
			)
			(layers "F.Cu" "F.Mask" "F.Paste")
			(net "SSD5_PERST_N")
		)
		(pad "B83" smd rect
			(at 27.599894 -1.131062 90)
			(size 0.508 2.4892)
			(drill
				(offset 0 0.381)
			)
			(layers "F.Cu" "F.Mask" "F.Paste")
			(net "PEER_1A&2A_HB")
		)
		(pad "B84" smd rect
			(at 28.399994 -1.131062 90)
			(size 0.508 2.4892)
			(drill
				(offset 0 0.381)
			)
			(layers "F.Cu" "F.Mask" "F.Paste")
			(net "SELF_1A&2A_HB")
		)
		(pad "B85" smd rect
			(at 29.200094 -1.131062 90)
			(size 0.508 2.4892)
			(drill
				(offset 0 0.381)
			)
			(layers "F.Cu" "F.Mask" "F.Paste")
			(net "FCB_HW_REVISION")
		)
		(pad "B86" smd rect
			(at 29.99994 -1.131062 90)
			(size 0.508 2.4892)
			(drill
				(offset 0 0.381)
			)
			(layers "F.Cu" "F.Mask" "F.Paste")
			(net "DPB_HW_REVISION")
		)
		(pad "B87" smd rect
			(at 30.80004 -1.131062 90)
			(size 0.508 2.4892)
			(drill
				(offset 0 0.381)
			)
			(layers "F.Cu" "F.Mask" "F.Paste")
			(net "SELF_TRAY_PRESENT_R")
		)
		(pad "B88" smd rect
			(at 31.599886 -1.131062 90)
			(size 0.508 2.4892)
			(drill
				(offset 0 0.381)
			)
			(layers "F.Cu" "F.Mask" "F.Paste")
			(net "PEER_TRAY_PRESENT")
		)
		(pad "B89" smd rect
			(at 32.399986 -1.131062 90)
			(size 0.508 2.4892)
			(drill
				(offset 0 0.381)
			)
			(layers "F.Cu" "F.Mask" "F.Paste")
			(net "GND")
		)
		(pad "B90" smd rect
			(at 33.200086 -1.131062 90)
			(size 0.508 2.4892)
			(drill
				(offset 0 0.381)
			)
			(layers "F.Cu" "F.Mask" "F.Paste")
			(net "GND")
		)
		(pad "B91" smd rect
			(at 33.999932 -1.131062 90)
			(size 0.508 2.4892)
			(drill
				(offset 0 0.381)
			)
			(layers "F.Cu" "F.Mask" "F.Paste")
			(net "GND")
		)
		(pad "B92" smd rect
			(at 34.800032 -1.131062 90)
			(size 0.508 2.4892)
			(drill
				(offset 0 0.381)
			)
			(layers "F.Cu" "F.Mask" "F.Paste")
			(net "GND")
		)
		(pad "B93" smd rect
			(at 35.599878 -1.131062 90)
			(size 0.508 2.4892)
			(drill
				(offset 0 0.381)
			)
			(layers "F.Cu" "F.Mask" "F.Paste")
			(net "GND")
		)
		(pad "B94" smd rect
			(at 36.399978 -1.131062 90)
			(size 0.508 2.4892)
			(drill
				(offset 0 0.381)
			)
			(layers "F.Cu" "F.Mask" "F.Paste")
			(net "GND")
		)
		(pad "B95" smd rect
			(at 37.200078 -1.131062 90)
			(size 0.508 2.4892)
			(drill
				(offset 0 0.381)
			)
			(layers "F.Cu" "F.Mask" "F.Paste")
			(net "P12V")
		)
		(pad "B96" smd rect
			(at 37.999924 -1.131062 90)
			(size 0.508 2.4892)
			(drill
				(offset 0 0.381)
			)
			(layers "F.Cu" "F.Mask" "F.Paste")
			(net "P12V")
		)
		(pad "B97" smd rect
			(at 38.800024 -1.131062 90)
			(size 0.508 2.4892)
			(drill
				(offset 0 0.381)
			)
			(layers "F.Cu" "F.Mask" "F.Paste")
			(net "P12V")
		)
		(pad "B98" smd rect
			(at 39.600124 -1.131062 90)
			(size 0.508 2.4892)
			(drill
				(offset 0 0.381)
			)
			(layers "F.Cu" "F.Mask" "F.Paste")
			(net "P12V")
		)
		(pad "B99" smd rect
			(at 40.39997 -1.131062 90)
			(size 0.508 2.4892)
			(drill
				(offset 0 0.381)
			)
			(layers "F.Cu" "F.Mask" "F.Paste")
			(net "P12V")
		)
		(pad "B100" smd rect
			(at 41.20007 -1.131062 90)
			(size 0.508 2.4892)
			(drill
				(offset 0 0.381)
			)
			(layers "F.Cu" "F.Mask" "F.Paste")
			(net "P12V")
		)
	)
)
